# T6G (Grand Teton) — schematic parts with pin connectivity, parts 8035–8073 of 8303; source: Cadence DE-HDL packaged netlist (pstxprt.dat, pstxnet.dat, pstchip.dat)

R11667  Q_RES  33.2 1% CHIP  pkg 0402LF  page 81 : 1 = FM_SMB_2_ALERT_GPU_ISO_R_N ; 2 = FM_SMB_2_ALERT_GPU_ISO_N

SW1  SW20S_DHNF10FQTR  SW20S_DHNF-10F-Q-T/R MECH  pkg SW20S_DHNF10FTVTR  page 167
  1  \1\  BI  = GND
  2  \2\  BI  = FM_FORCE_ALL_PWRON_ON
  3  \3\  BI  = GND
  4  \4\  BI  = PU_BIOS_USB_RECOVERY
  5  \5\  BI  = PU_FPGA_DEBUG_SW_SPARE
  6  \6\  BI  = PD_BIOS_DEBUG_MODE
  7  \7\  BI  = PRSNT_CPU0_N
  8  \8\  BI  = PRSNT_CPU1_N
  9  \9\  BI  = GND
  10  \10\  BI  = PU_FPGA_DEBUG_LED_CTRL
  11  \11\  BI  = FM_SPD_CPU0_SWITCH_CTRL_N
  12  \12\  BI  = FM_FORCE_ALL_PWRON
  13  \13\  BI  = BMC_JTAG_SEL
  14  \14\  BI  = FM_BIOS_USB_RECOVERY
  15  \15\  BI  = FPGA_DEBUG_SW_SPARE
  16  \16\  BI  = BIOS_DEBUG_MODE
  17  \17\  BI  = FM_PRSNT_CPU0_N
  18  \18\  BI  = FM_PRSNT_CPU1_N
  19  \19\  BI  = FM_PASSWORD_CLEAR_N
  20  \20\  BI  = FPGA_DEBUG_LED_CTRL

TP1  TP  NA  pkg TP  page 27 : 1 = VSENSE_VSS_SENSE_A_P0
TP2  TP  NA  pkg TP  page 27 : 1 = VSENSE_VSS_SENSE_B_P0
TP3  TP  NA  pkg TP  page 27 : 1 = VSENSE_VSS_SENSE_C_P0
TP4  TP  NA  pkg TP  page 27 : 1 = VSENSE_PVDD18_S5_P0_DN
TP5  TP  NA  pkg TP  page 27 : 1 = VSENSE_PVDDIO_P0_DP
TP6  TP  NA  pkg TP  page 27 : 1 = VSENSE_PVDDCR_CPU1_P0_DP
TP7  TP  NA  pkg TP  page 27 : 1 = VSENSE_PVDDCR_CPU0_P0_DP
TP8  TP  NA  pkg TP  page 27 : 1 = VSENSE_PVDD11_S3_P0_DP
TP9  TP  NA  pkg TP  page 27 : 1 = VSENSE_PVDD18_S5_P0_DP
TP10  TP  NA  pkg TP  page 27 : 1 = VSENSE_PVDDCR_SOC_P0_DP
TP11  TP  NA  pkg TP  page 54 : 1 = VSENSE_VSS_SENSE_A_P1
TP12  TP  NA  pkg TP  page 54 : 1 = VSENSE_VSS_SENSE_B_P1
TP13  TP  NA  pkg TP  page 54 : 1 = VSENSE_VSS_SENSE_C_P1
TP14  TP  NA  pkg TP  page 54 : 1 = VSENSE_PVDD18_S5_P1_DN
TP15  TP  NA  pkg TP  page 54 : 1 = VSENSE_PVDDIO_P1_DP
TP16  TP  NA  pkg TP  page 54 : 1 = VSENSE_PVDDCR_CPU1_P1_DP
TP17  TP  NA  pkg TP  page 54 : 1 = VSENSE_PVDDCR_CPU0_P1_DP
TP18  TP  NA  pkg TP  page 54 : 1 = VSENSE_PVDD11_S3_P1_DP
TP19  TP  NA  pkg TP  page 54 : 1 = VSENSE_PVDD18_S5_P1_DP
TP20  TP  NA  pkg TP  page 54 : 1 = VSENSE_PVDDCR_SOC_P1_DP

U1  M24128BWMN6TP  M24128-BWMN6TP IC  pkg SOIC8XH  page 238
  1  E0  IN  = CPU_FRU_ADDR0
  2  E1  IN  = CPU_FRU_ADDR1
  3  E2  IN  = CPU_FRU_ADDR2
  4  VSS  POWER  = GND
  5  SDA  BI  = SMB_CPU_FRU_3V3AUX_SDA
  6  SCL  IN  = SMB_CPU_FRU_3V3AUX_SCL
  7  \wc#\  IN  = PD_CPU_FRU_WP
  8  VCC  POWER  = P3V3_AUX

U2  PCA9617ADP  IC  pkg TSSOP8_3XB  page 160
  1  VCCA  POWER  = PVDD11_S3_P0
  2  SCLA  BI  = SMB_CPU0_CPU1_APML_BUF2_SCL_R1
  3  SDAA  BI  = SMB_CPU0_CPU1_APML_BUF2_SDA_R1
  4  GND  POWER  = GND
  5  EN  IN  = PU_U2_EN
  6  SDAB  BI  = SMB_CPU0_CPU1_APML_BUF2_SDA
  7  SCLB  BI  = SMB_CPU0_CPU1_APML_BUF2_SCL
  8  VCCB  POWER  = P3V3_AUX

U3  SN74LVC1G07DBVR  IC  pkg SMLF  page 29
  1  NC  TRI  = NC
  2  A  IN  = SCM_USB_OC_N
  3  GND  POWER  = GND
  4  Y  OCA  = SCM_USB_OC_BU_R_N
  5  VCC  POWER  = P1V8_AUX

U4  PI3CSW12ZUAEX  IC  pkg UQFN10_0-5_2X1-5  page 161
  1  \1d+\  BI  = SMB_APML_CPU0_MUX2_SCL
  2  \1d-\  BI  = SMB_APML_CPU0_MUX2_SDA
  3  \2d+\  BI  = SMB_APML_CPU1_MUX2_SCL
  4  \2d-\  BI  = SMB_APML_CPU1_MUX2_SDA
  5  GND  POWER  = GND
  6  \oe#\  IN  = FM_APML_MUX2_OE_N
  7  \d-\  BI  = SMB_CPU0_CPU1_APML_MUX2_SDA
  8  \d+\  BI  = SMB_CPU0_CPU1_APML_MUX2_SCL
  9  S  IN  = FM_APML_MUX2_SEL
  10  VDD  POWER  = P3V3_AUX

U5  PCA9617ADP  EMPTY  pkg TSSOP8_3XB  page 160
  1  VCCA  POWER  = P3V3_AUX
  2  SCLA  BI  = SMB_CPU0_CPU1_APML_BUF1_SCL
  3  SDAA  BI  = SMB_CPU0_CPU1_APML_BUF1_SDA
  4  GND  POWER  = GND
  5  EN  IN  = PU_U5_EN
  6  SDAB  BI  = SMB_CPU0_CPU1_APML_BUF1_SDA_R1
  7  SCLB  BI  = SMB_CPU0_CPU1_APML_BUF1_SCL_R1
  8  VCCB  POWER  = P3V3

U6  PI3CSW12ZUAEX  IC  pkg UQFN10_0-5_2X1-5  page 161
  1  \1d+\  BI  = SMB_CPU0_SEC_R_SCL
  2  \1d-\  BI  = SMB_CPU0_SEC_R_SDA
  3  \2d+\  BI  = SMB_CPU1_SEC_R_SCL
  4  \2d-\  BI  = SMB_CPU1_SEC_R_SDA
  5  GND  POWER  = GND
  6  \oe#\  IN  = FM_SEC_MUX_OE_N
  7  \d-\  BI  = SMB_CPU0_CPU1_SEC_SDA_R2
  8  \d+\  BI  = SMB_CPU0_CPU1_SEC_SCL_R2
  9  S  IN  = FM_SEC_MUX_SEL
  10  VDD  POWER  = P3V3_AUX

U7  74CBTLV3126PW  IC  pkg TSSOP14  page 132
  1  \1oe\  IN  = FB_BMC_ISOLATE
  2  \1a\  POWER  = NCSI_BMC_TXD1_R
  3  \1b\  BI  = NCSI_OCP_SFF_TXD1
  4  \2oe\  OUT  = FB_BMC_ISOLATE
  5  \2a\  BI  = NCSI_BMC_TXD0_R
  6  \2b\  BI  = NCSI_OCP_SFF_TXD0
  7  GND  POWER  = GND
  8  \3b\  BI  = NCSI_OCP_SFF_TX_EN
  9  \3a\  BI  = NCSI_BMC_TX_EN_R
  10  \3oe\  BI  = FB_BMC_ISOLATE
  11  \4b\  BI  = OCP_SFF_ISO2_RBT_ARB_OUT
  12  \4a\  BI  = OCP_SFF_RBT_ARB_OUT
  13  \4oe\  BI  = FB_BMC_ISOLATE
  14  VCC  BI  = P3V3_AUX

U8  74LVC2G07DW7  74LVC2G07DW-7 IC  pkg SOT363_0-65_2X1-25XC  page 134
  1  \1a\  IN  = OCP_SFF_PRSNT2_R_N
  2  GND  POWER  = GND
  3  \2a\  IN  = OCP_SFF_PRSNT3_R_N
  4  \2y\  OUT  = HP_LVC3_OCP_V3_1_PRSNT2_N_R
  5  VCC  POWER  = P3V3_AUX
  6  \1y\  OUT  = HP_LVC3_OCP_V3_1_PRSNT2_N_R

U9  TPS71715DCKR  EMPTY  pkg SC70-5XB  page 187
  1  \in\  IN  = P1V5_BAT_IN
  2  GND  POWER  = GND
  3  EN  IN  = BAT_LDO_EN
  4  \nr||fb\  OUT  = U9_NR
  5  \out\  OUT  = P1V5_BAT_OUT

U10  9ZXL0451EKILFT  IC  pkg VFQFPN32_TH_0-5_5X5XD  page 183
  1  \^ckpwrgd_pd#\  IN  = FM_9ZXL045_P1_DEV_EN
  2  VDDR  POWER  = P3V3_9ZXL045_P1_VDDR
  3  DIF_IN  IN  = CLK_100M_CPU1_CLK13_DP
  4  \dif_in#\  IN  = CLK_100M_CPU1_CLK13_DN
  5  VSADR0_TRI  IN  = CLK_9ZXL045_P1_SADR0
  6  SMBDAT  BI  = SMB_9ZXL045_P1_SDA
  7  SMBCLK  IN  = SMB_9ZXL045_P1_SCL
  8  \fbout_nc#\  OUT  = NC_U10_FBOUT_N
  9  FBOUT_NC  OUT  = NC_U10_FBOUT
  10  NC0  TRI  = NC_U10_NC0
  11  NC1  TRI  = NC_U10_NC1
  12  VDD0  POWER  = P3V3_9ZXL045_P1_VDD
  13  DIF0  OUT  = CLK_100M_RETIMER_CPU1_P0_R_DP
  14  \dif0#\  OUT  = CLK_100M_RETIMER_CPU1_P0_R_DN
  15  \voe0#\  IN  = FM_9ZXL045_P1_0_OE_N
  16  VDD1  POWER  = P3V3_9ZXL045_P1_VDD
  17  NC2  TRI  = NC_U10_NC2
  18  \voe1#\  IN  = FM_9ZXL045_P1_1_OE_N
  19  DIF1  OUT  = CLK_100M_RETIMER_CPU1_P1_R_DP
  20  \dif1#\  OUT  = CLK_100M_RETIMER_CPU1_P1_R_DN
  21  VDD2  POWER  = P3V3_9ZXL045_P1_VDD
  22  DIF2  OUT  = CLK_100M_RETIMER_CPU1_P2_R_DP
  23  \dif2#\  OUT  = CLK_100M_RETIMER_CPU1_P2_R_DN
  24  \voe2#\  IN  = FM_9ZXL045_P1_2_OE_N
  25  VDD3  POWER  = P3V3_9ZXL045_P1_VDD
  26  \voe3#\  IN  = FM_9ZXL045_P1_3_OE_N
  27  DIF3  OUT  = CLK_100M_RETIMER_CPU1_P3_R_DP
  28  \dif3#\  OUT  = CLK_100M_RETIMER_CPU1_P3_R_DN
  29  VDD4  POWER  = P3V3_9ZXL045_P1_VDD
  30  NC3  TRI  = NC_U10_NC3
  31  VDDA  POWER  = P3V3_9ZXL045_P1_VDDA
  32  \^hibw_bypm_lobw#\  IN  = CLK_9ZXL045_P1_HIBW
  33  EPAD_GND  POWER  = GND

U11  M24M02DRMN6TP  M24M02-DRMN6TP IC  pkg SOIC8XH  page 278
  1  DU1  IN  = NC
  2  DU2  IN  = NC
  3  E2  IN  = U11_E2
  4  VSS  POWER  = GND
  5  SDA  BI  = SMB_RT_CPU0_P0_ROM_SDA
  6  SCL  IN  = SMB_RT_CPU0_P0_ROM_SCL
  7  WC_N  IN  = GND
  8  VCC  POWER  = P1V8_CPU0_RT_1D

U12  M24M02DRMN6TP  M24M02-DRMN6TP IC  pkg SOIC8XH  page 322
  1  DU1  IN  = NC
  2  DU2  IN  = NC
  3  E2  IN  = U12_E2
  4  VSS  POWER  = GND
  5  SDA  BI  = SMB_RT_CPU1_P0_ROM_SDA
  6  SCL  IN  = SMB_RT_CPU1_P0_ROM_SCL
  7  WC_N  IN  = GND
  8  VCC  POWER  = P1V8_CPU1_RT_1D

U13  SN74AUC2G66DCTR  IC  pkg SSOP8  page 174
  1  \1a\  BI  = JTAG_CPU0_TDO
  2  \1b\  BI  = JTAG_CPU0_TDO_CPU1_TDI
  3  \2c\  BI  = FM_PLD_CPU0_PRSNT_HDT_N
  4  GND  POWER  = GND
  5  \2a\  BI  = JTAG_CPU0_BYPASS_R1
  6  \2b\  BI  = JTAG_CPU0_TDO_CPU1_TDI_R1
  7  \1c\  BI  = CPU0_HDT_BYPASS_SEL
  8  VCC  POWER  = PVDD18_S5_P0

U14  SN74AUC2G66DCTR  IC  pkg SSOP8  page 174
  1  \1a\  BI  = JTAG_CPU0_TDO_CPU1_TDI
  2  \1b\  BI  = JTAG_CPU1_R_TDI
  3  \2c\  BI  = FM_PLD_CPU1_PRSNT_HDT_N
  4  GND  POWER  = GND
  5  \2a\  BI  = JTAG_CPU0_TDO_CPU1_TDI
  6  \2b\  BI  = JTAG_CPU1_BYPASS
  7  \1c\  BI  = CPU1_HDT_BYPASS_SEL
  8  VCC  POWER  = PVDD18_S5_P0

U15  M24M02DRMN6TP  M24M02-DRMN6TP IC  pkg SOIC8XH  page 289
  1  DU1  IN  = NC
  2  DU2  IN  = NC
  3  E2  IN  = U15_E2
  4  VSS  POWER  = GND
  5  SDA  BI  = SMB_RT_CPU0_P1_ROM_SDA
  6  SCL  IN  = SMB_RT_CPU0_P1_ROM_SCL
  7  WC_N  IN  = GND
  8  VCC  POWER  = P1V8_CPU0_RT_1D

U16  M24M02DRMN6TP  M24M02-DRMN6TP IC  pkg SOIC8XH  page 300
  1  DU1  IN  = NC
  2  DU2  IN  = NC
  3  E2  IN  = U16_E2
  4  VSS  POWER  = GND
  5  SDA  BI  = SMB_RT_CPU0_P2_ROM_SDA
  6  SCL  IN  = SMB_RT_CPU0_P2_ROM_SCL
  7  WC_N  IN  = GND
  8  VCC  POWER  = P1V8_CPU0_RT_1D

U17  M24M02DRMN6TP  M24M02-DRMN6TP IC  pkg SOIC8XH  page 311
  1  DU1  IN  = NC
  2  DU2  IN  = NC
  3  E2  IN  = U17_E2
  4  VSS  POWER  = GND
  5  SDA  BI  = SMB_RT_CPU0_P3_ROM_SDA
  6  SCL  IN  = SMB_RT_CPU0_P3_ROM_SCL
  7  WC_N  IN  = GND
  8  VCC  POWER  = P1V8_CPU0_RT_1D
